(kicad_pcb
	(version 20260206)
	(generator "pcbnew")
	(generator_version "10.0")
	(general
		(thickness 1.6)
		(legacy_teardrops no)
	)
	(paper "A4")
	(title_block
		(title "Wiwynn_Tioga_Pass_MB.brd")
		(comment 1 "Tioga Pass / footprints 2559-2565 of 4770")
	)
	(layers
		(0 "F.Cu" signal "TOP")
		(4 "In1.Cu" signal "L2GND")
		(6 "In2.Cu" signal "L3")
		(8 "In3.Cu" signal "L4GND")
		(10 "In4.Cu" signal "L5")
		(12 "In5.Cu" signal "L6GND")
		(14 "In6.Cu" signal "L7VCC")
		(16 "In7.Cu" signal "L8VCC")
		(18 "In8.Cu" signal "L9GND")
		(20 "In9.Cu" signal "L10")
		(22 "In10.Cu" signal "L11GND")
		(24 "In11.Cu" signal "L12")
		(26 "In12.Cu" signal "L13GND")
		(2 "B.Cu" signal "BOTTOM")
		(9 "F.Adhes" user "F.Adhesive")
		(11 "B.Adhes" user "B.Adhesive")
		(13 "F.Paste" user "Package Geometry/Pastemask Top")
		(15 "B.Paste" user "Package Geometry/Pastemask Bottom")
		(5 "F.SilkS" user "Ref Des/Silkscreen Top")
		(7 "B.SilkS" user "Ref Des/Silkscreen Bottom")
		(1 "F.Mask" user "Board Geometry/Soldermask Top")
		(3 "B.Mask" user "Board Geometry/Soldermask Bottom")
		(17 "Dwgs.User" user "User.Drawings")
		(19 "Cmts.User" user "User.Comments")
		(21 "Eco1.User" user "User.Eco1")
		(23 "Eco2.User" user "User.Eco2")
		(25 "Edge.Cuts" user "Board Geometry/Outline")
		(27 "Margin" user)
		(31 "F.CrtYd" user "Package Geometry/Place Bound Top")
		(29 "B.CrtYd" user "Package Geometry/Place Bound Bottom")
		(35 "F.Fab" user "Ref Des/Assembly Top")
		(33 "B.Fab" user "Ref Des/Assembly Bottom")
	)
	(footprint ""
		(layer "B.Cu")
		(at 365.506 -110.998 -90)
		(property "Reference" "C3N9"
			(at 0 0 90)
			(layer "B.SilkS")
			(hide yes)
			(effects
				(font
					(size 1.27 1.27)
				)
				(justify mirror)
			)
		)
		(property "Value" ""
			(at 0 0 90)
			(layer "B.Fab")
			(effects
				(font
					(size 1.27 1.27)
				)
				(justify mirror)
			)
		)
		(duplicate_pad_numbers_are_jumpers no)
		(fp_poly
			(pts
				(xy -0.3048 -0.1016) (xy -0.3048 0.9906) (xy 0.3048 0.9906) (xy 0.3048 -0.1016)
			)
			(stroke
				(width 0)
				(type default)
			)
			(fill no)
			(layer "B.CrtYd")
		)
		(fp_line
			(start -0.3048 0.9906)
			(end -0.3048 -0.1016)
			(stroke
				(width 0.1)
				(type default)
			)
			(layer "B.Fab")
		)
		(fp_line
			(start 0.3048 0.9906)
			(end -0.3048 0.9906)
			(stroke
				(width 0.1)
				(type default)
			)
			(layer "B.Fab")
		)
		(fp_line
			(start -0.3048 -0.1016)
			(end 0.3048 -0.1016)
			(stroke
				(width 0.1)
				(type default)
			)
			(layer "B.Fab")
		)
		(fp_line
			(start 0.3048 -0.1016)
			(end 0.3048 0.9906)
			(stroke
				(width 0.1)
				(type default)
			)
			(layer "B.Fab")
		)
		(pad "1" smd rect
			(at 0 0 90)
			(size 0.508 0.508)
			(layers "B.Cu" "B.Mask" "B.Paste")
			(net "DMI_CPU0_PCH_RX_DP<2>")
		)
		(pad "2" smd rect
			(at 0 0.889 90)
			(size 0.508 0.508)
			(layers "B.Cu" "B.Mask" "B.Paste")
			(net "DMI_CPU0_PCH_RX_C_DP<2>")
		)
		(zone
			(layer "B.Cu")
			(hatch none 0.5)
			(connect_pads
				(clearance 0)
			)
			(min_thickness 0.25)
			(keepout
				(tracks not_allowed)
				(vias allowed)
				(pads allowed)
				(copperpour not_allowed)
				(footprints allowed)
			)
			(placement
				(enabled no)
				(sheetname "")
			)
			(fill
				(thermal_gap 0.5)
				(thermal_bridge_width 0.5)
				(island_removal_mode 0)
			)
			(polygon
				(pts
					(xy 364.871 -110.744) (xy 364.871 -111.252) (xy 365.252 -111.252) (xy 365.252 -110.744)
				)
			)
		)
		(zone
			(layer "B.Cu")
			(hatch none 0.5)
			(connect_pads
				(clearance 0)
			)
			(min_thickness 0.25)
			(keepout
				(tracks allowed)
				(vias not_allowed)
				(pads allowed)
				(copperpour not_allowed)
				(footprints allowed)
			)
			(placement
				(enabled no)
				(sheetname "")
			)
			(fill
				(thermal_gap 0.5)
				(thermal_bridge_width 0.5)
				(island_removal_mode 0)
			)
			(polygon
				(pts
					(xy 365.252 -110.744) (xy 365.252 -111.252) (xy 364.871 -111.252) (xy 364.871 -110.744)
				)
			)
		)
	)
	(footprint ""
		(layer "B.Cu")
		(at 330.08316 -66.25336 90)
		(property "Reference" "R4P12"
			(at 0 0 90)
			(layer "B.SilkS")
			(hide yes)
			(effects
				(font
					(size 1.27 1.27)
				)
				(justify mirror)
			)
		)
		(property "Value" ""
			(at 0 0 90)
			(layer "B.Fab")
			(effects
				(font
					(size 1.27 1.27)
				)
				(justify mirror)
			)
		)
		(duplicate_pad_numbers_are_jumpers no)
		(fp_poly
			(pts
				(xy 0.2794 -0.1016) (xy -0.2794 -0.1016) (xy -0.2794 0.9906) (xy 0.2794 0.9906)
			)
			(stroke
				(width 0)
				(type default)
			)
			(fill no)
			(layer "B.CrtYd")
		)
		(fp_line
			(start 0.2794 -0.1016)
			(end 0.2794 0.9906)
			(stroke
				(width 0.1)
				(type default)
			)
			(layer "B.Fab")
		)
		(fp_line
			(start -0.2794 -0.1016)
			(end 0.2794 -0.1016)
			(stroke
				(width 0.1)
				(type default)
			)
			(layer "B.Fab")
		)
		(fp_line
			(start 0.2794 0.9906)
			(end -0.2794 0.9906)
			(stroke
				(width 0.1)
				(type default)
			)
			(layer "B.Fab")
		)
		(fp_line
			(start -0.2794 0.9906)
			(end -0.2794 -0.1016)
			(stroke
				(width 0.1)
				(type default)
			)
			(layer "B.Fab")
		)
		(pad "1" smd rect
			(at 0 0 270)
			(size 0.508 0.508)
			(layers "B.Cu" "B.Mask" "B.Paste")
			(net "PVCCIO_CPU0")
		)
		(pad "2" smd rect
			(at 0 0.889 270)
			(size 0.508 0.508)
			(layers "B.Cu" "B.Mask" "B.Paste")
			(net "XDP_CPU_MBP0_N")
		)
		(zone
			(layer "B.Cu")
			(hatch none 0.5)
			(connect_pads
				(clearance 0)
			)
			(min_thickness 0.25)
			(keepout
				(tracks allowed)
				(vias not_allowed)
				(pads allowed)
				(copperpour not_allowed)
				(footprints allowed)
			)
			(placement
				(enabled no)
				(sheetname "")
			)
			(fill
				(thermal_gap 0.5)
				(thermal_bridge_width 0.5)
				(island_removal_mode 0)
			)
			(polygon
				(pts
					(xy 330.33716 -66.50736) (xy 330.33716 -65.99936) (xy 330.71816 -65.99936) (xy 330.71816 -66.50736)
				)
			)
		)
		(zone
			(layer "B.Cu")
			(hatch none 0.5)
			(connect_pads
				(clearance 0)
			)
			(min_thickness 0.25)
			(keepout
				(tracks not_allowed)
				(vias allowed)
				(pads allowed)
				(copperpour not_allowed)
				(footprints allowed)
			)
			(placement
				(enabled no)
				(sheetname "")
			)
			(fill
				(thermal_gap 0.5)
				(thermal_bridge_width 0.5)
				(island_removal_mode 0)
			)
			(polygon
				(pts
					(xy 330.71816 -66.50736) (xy 330.71816 -65.99936) (xy 330.33716 -65.99936) (xy 330.33716 -66.50736)
				)
			)
		)
	)
	(footprint ""
		(layer "B.Cu")
		(at 375.7041 -110.281212)
		(property "Reference" "C3W1"
			(at 0.8382 -0.67818 0)
			(unlocked yes)
			(layer "B.SilkS")
			(effects
				(font
					(size 0.4064 0.254)
					(thickness 0.1524)
				)
				(justify left mirror)
			)
		)
		(property "Value" ""
			(at 0 0 0)
			(layer "B.Fab")
			(effects
				(font
					(size 1.27 1.27)
				)
				(justify mirror)
			)
		)
		(duplicate_pad_numbers_are_jumpers no)
		(fp_poly
			(pts
				(xy -0.3048 -0.1016) (xy -0.3048 0.9906) (xy 0.3048 0.9906) (xy 0.3048 -0.1016)
			)
			(stroke
				(width 0)
				(type default)
			)
			(fill no)
			(layer "B.CrtYd")
		)
		(fp_line
			(start -0.3048 -0.1016)
			(end 0.3048 -0.1016)
			(stroke
				(width 0.1)
				(type default)
			)
			(layer "B.Fab")
		)
		(fp_line
			(start -0.3048 0.9906)
			(end -0.3048 -0.1016)
			(stroke
				(width 0.1)
				(type default)
			)
			(layer "B.Fab")
		)
		(fp_line
			(start 0.3048 -0.1016)
			(end 0.3048 0.9906)
			(stroke
				(width 0.1)
				(type default)
			)
			(layer "B.Fab")
		)
		(fp_line
			(start 0.3048 0.9906)
			(end -0.3048 0.9906)
			(stroke
				(width 0.1)
				(type default)
			)
			(layer "B.Fab")
		)
		(pad "1" smd rect
			(at 0 0 180)
			(size 0.508 0.508)
			(layers "B.Cu" "B.Mask" "B.Paste")
			(net "A_PCH_XCLK_BIASREF")
		)
		(pad "2" smd rect
			(at 0 0.889 180)
			(size 0.508 0.508)
			(layers "B.Cu" "B.Mask" "B.Paste")
			(net "GND")
		)
		(zone
			(layer "B.Cu")
			(hatch none 0.5)
			(connect_pads
				(clearance 0)
			)
			(min_thickness 0.25)
			(keepout
				(tracks allowed)
				(vias not_allowed)
				(pads allowed)
				(copperpour not_allowed)
				(footprints allowed)
			)
			(placement
				(enabled no)
				(sheetname "")
			)
			(fill
				(thermal_gap 0.5)
				(thermal_bridge_width 0.5)
				(island_removal_mode 0)
			)
			(polygon
				(pts
					(xy 375.9581 -110.027212) (xy 375.4501 -110.027212) (xy 375.4501 -109.646212) (xy 375.9581 -109.646212)
				)
			)
		)
		(zone
			(layer "B.Cu")
			(hatch none 0.5)
			(connect_pads
				(clearance 0)
			)
			(min_thickness 0.25)
			(keepout
				(tracks not_allowed)
				(vias allowed)
				(pads allowed)
				(copperpour not_allowed)
				(footprints allowed)
			)
			(placement
				(enabled no)
				(sheetname "")
			)
			(fill
				(thermal_gap 0.5)
				(thermal_bridge_width 0.5)
				(island_removal_mode 0)
			)
			(polygon
				(pts
					(xy 375.9581 -109.646212) (xy 375.4501 -109.646212) (xy 375.4501 -110.027212) (xy 375.9581 -110.027212)
				)
			)
		)
	)
	(footprint ""
		(layer "B.Cu")
		(at 495.2492 -137.7569 180)
		(property "Reference" "R1L32"
			(at 0 0 0)
			(layer "B.SilkS")
			(hide yes)
			(effects
				(font
					(size 1.27 1.27)
				)
				(justify mirror)
			)
		)
		(property "Value" ""
			(at 0 0 0)
			(layer "B.Fab")
			(effects
				(font
					(size 1.27 1.27)
				)
				(justify mirror)
			)
		)
		(duplicate_pad_numbers_are_jumpers no)
		(fp_poly
			(pts
				(xy 0.2794 -0.1016) (xy -0.2794 -0.1016) (xy -0.2794 0.9906) (xy 0.2794 0.9906)
			)
			(stroke
				(width 0)
				(type default)
			)
			(fill no)
			(layer "B.CrtYd")
		)
		(fp_line
			(start 0.2794 0.9906)
			(end -0.2794 0.9906)
			(stroke
				(width 0.1)
				(type default)
			)
			(layer "B.Fab")
		)
		(fp_line
			(start 0.2794 -0.1016)
			(end 0.2794 0.9906)
			(stroke
				(width 0.1)
				(type default)
			)
			(layer "B.Fab")
		)
		(fp_line
			(start -0.2794 0.9906)
			(end -0.2794 -0.1016)
			(stroke
				(width 0.1)
				(type default)
			)
			(layer "B.Fab")
		)
		(fp_line
			(start -0.2794 -0.1016)
			(end 0.2794 -0.1016)
			(stroke
				(width 0.1)
				(type default)
			)
			(layer "B.Fab")
		)
		(pad "1" smd rect
			(at 0 0)
			(size 0.508 0.508)
			(layers "B.Cu" "B.Mask" "B.Paste")
			(net "LED_POSTCODE_0")
		)
		(pad "2" smd rect
			(at 0 0.889)
			(size 0.508 0.508)
			(layers "B.Cu" "B.Mask" "B.Paste")
			(net "LED_POSTCODE_0_R")
		)
		(zone
			(layer "B.Cu")
			(hatch none 0.5)
			(connect_pads
				(clearance 0)
			)
			(min_thickness 0.25)
			(keepout
				(tracks not_allowed)
				(vias allowed)
				(pads allowed)
				(copperpour not_allowed)
				(footprints allowed)
			)
			(placement
				(enabled no)
				(sheetname "")
			)
			(fill
				(thermal_gap 0.5)
				(thermal_bridge_width 0.5)
				(island_removal_mode 0)
			)
			(polygon
				(pts
					(xy 494.9952 -138.3919) (xy 495.5032 -138.3919) (xy 495.5032 -138.0109) (xy 494.9952 -138.0109)
				)
			)
		)
		(zone
			(layer "B.Cu")
			(hatch none 0.5)
			(connect_pads
				(clearance 0)
			)
			(min_thickness 0.25)
			(keepout
				(tracks allowed)
				(vias not_allowed)
				(pads allowed)
				(copperpour not_allowed)
				(footprints allowed)
			)
			(placement
				(enabled no)
				(sheetname "")
			)
			(fill
				(thermal_gap 0.5)
				(thermal_bridge_width 0.5)
				(island_removal_mode 0)
			)
			(polygon
				(pts
					(xy 494.9952 -138.0109) (xy 495.5032 -138.0109) (xy 495.5032 -138.3919) (xy 494.9952 -138.3919)
				)
			)
		)
	)
	(footprint ""
		(layer "B.Cu")
		(at 467.106 -46.6725 180)
		(property "Reference" "R9E10"
			(at 0 0 0)
			(layer "B.SilkS")
			(hide yes)
			(effects
				(font
					(size 1.27 1.27)
				)
				(justify mirror)
			)
		)
		(property "Value" ""
			(at 0 0 0)
			(layer "B.Fab")
			(effects
				(font
					(size 1.27 1.27)
				)
				(justify mirror)
			)
		)
		(duplicate_pad_numbers_are_jumpers no)
		(fp_poly
			(pts
				(xy 0.2794 -0.1016) (xy -0.2794 -0.1016) (xy -0.2794 0.9906) (xy 0.2794 0.9906)
			)
			(stroke
				(width 0)
				(type default)
			)
			(fill no)
			(layer "B.CrtYd")
		)
		(fp_line
			(start 0.2794 0.9906)
			(end -0.2794 0.9906)
			(stroke
				(width 0.1)
				(type default)
			)
			(layer "B.Fab")
		)
		(fp_line
			(start 0.2794 -0.1016)
			(end 0.2794 0.9906)
			(stroke
				(width 0.1)
				(type default)
			)
			(layer "B.Fab")
		)
		(fp_line
			(start -0.2794 0.9906)
			(end -0.2794 -0.1016)
			(stroke
				(width 0.1)
				(type default)
			)
			(layer "B.Fab")
		)
		(fp_line
			(start -0.2794 -0.1016)
			(end 0.2794 -0.1016)
			(stroke
				(width 0.1)
				(type default)
			)
			(layer "B.Fab")
		)
		(pad "1" smd rect
			(at 0 0)
			(size 0.508 0.508)
			(layers "B.Cu" "B.Mask" "B.Paste")
			(net "RST_PCIE_CPU_DEV1_R_N")
		)
		(pad "2" smd rect
			(at 0 0.889)
			(size 0.508 0.508)
			(layers "B.Cu" "B.Mask" "B.Paste")
			(net "RST_PCIE_CPU_DEV1_N")
		)
		(zone
			(layer "B.Cu")
			(hatch none 0.5)
			(connect_pads
				(clearance 0)
			)
			(min_thickness 0.25)
			(keepout
				(tracks not_allowed)
				(vias allowed)
				(pads allowed)
				(copperpour not_allowed)
				(footprints allowed)
			)
			(placement
				(enabled no)
				(sheetname "")
			)
			(fill
				(thermal_gap 0.5)
				(thermal_bridge_width 0.5)
				(island_removal_mode 0)
			)
			(polygon
				(pts
					(xy 466.852 -47.3075) (xy 467.36 -47.3075) (xy 467.36 -46.9265) (xy 466.852 -46.9265)
				)
			)
		)
		(zone
			(layer "B.Cu")
			(hatch none 0.5)
			(connect_pads
				(clearance 0)
			)
			(min_thickness 0.25)
			(keepout
				(tracks allowed)
				(vias not_allowed)
				(pads allowed)
				(copperpour not_allowed)
				(footprints allowed)
			)
			(placement
				(enabled no)
				(sheetname "")
			)
			(fill
				(thermal_gap 0.5)
				(thermal_bridge_width 0.5)
				(island_removal_mode 0)
			)
			(polygon
				(pts
					(xy 466.852 -46.9265) (xy 467.36 -46.9265) (xy 467.36 -47.3075) (xy 466.852 -47.3075)
				)
			)
		)
	)
	(footprint ""
		(layer "B.Cu")
		(at 463.042 -116.49202)
		(property "Reference" "C1M8"
			(at 0 0 0)
			(layer "B.SilkS")
			(hide yes)
			(effects
				(font
					(size 1.27 1.27)
				)
				(justify mirror)
			)
		)
		(property "Value" ""
			(at 0 0 0)
			(layer "B.Fab")
			(effects
				(font
					(size 1.27 1.27)
				)
				(justify mirror)
			)
		)
		(duplicate_pad_numbers_are_jumpers no)
		(fp_rect
			(start -0.3048 0.9906)
			(end 0.3048 -0.1016)
			(stroke
				(width 0)
				(type default)
			)
			(fill no)
			(layer "B.CrtYd")
		)
		(fp_line
			(start -0.3048 -0.1016)
			(end 0.3048 -0.1016)
			(stroke
				(width 0.1)
				(type default)
			)
			(layer "B.Fab")
		)
		(fp_line
			(start -0.3048 0.9906)
			(end -0.3048 -0.1016)
			(stroke
				(width 0.1)
				(type default)
			)
			(layer "B.Fab")
		)
		(fp_line
			(start 0.3048 -0.1016)
			(end 0.3048 0.9906)
			(stroke
				(width 0.1)
				(type default)
			)
			(layer "B.Fab")
		)
		(fp_line
			(start 0.3048 0.9906)
			(end -0.3048 0.9906)
			(stroke
				(width 0.1)
				(type default)
			)
			(layer "B.Fab")
		)
		(pad "1" smd rect
			(at 0 0 180)
			(size 0.508 0.508)
			(layers "B.Cu" "B.Mask" "B.Paste")
			(net "P3E_CPU0_PE3_OCP_TXP<14>")
		)
		(pad "2" smd rect
			(at 0 0.889 180)
			(size 0.508 0.508)
			(layers "B.Cu" "B.Mask" "B.Paste")
			(net "P3E_OCP_CPU0_PE3_C_TXP<14>")
		)
		(zone
			(layer "B.Cu")
			(hatch none 0.5)
			(connect_pads
				(clearance 0)
			)
			(min_thickness 0.25)
			(keepout
				(tracks allowed)
				(vias not_allowed)
				(pads allowed)
				(copperpour not_allowed)
				(footprints allowed)
			)
			(placement
				(enabled no)
				(sheetname "")
			)
			(fill
				(thermal_gap 0.5)
				(thermal_bridge_width 0.5)
				(island_removal_mode 0)
			)
			(polygon
				(pts
					(xy 462.788 -115.85702) (xy 463.296 -115.85702) (xy 463.296 -116.23802) (xy 462.788 -116.23802)
				)
			)
		)
		(zone
			(layer "B.Cu")
			(hatch none 0.5)
			(connect_pads
				(clearance 0)
			)
			(min_thickness 0.25)
			(keepout
				(tracks not_allowed)
				(vias allowed)
				(pads allowed)
				(copperpour not_allowed)
				(footprints allowed)
			)
			(placement
				(enabled no)
				(sheetname "")
			)
			(fill
				(thermal_gap 0.5)
				(thermal_bridge_width 0.5)
				(island_removal_mode 0)
			)
			(polygon
				(pts
					(xy 462.788 -115.85702) (xy 463.296 -115.85702) (xy 463.296 -116.23802) (xy 462.788 -116.23802)
				)
			)
		)
	)
	(footprint ""
		(layer "B.Cu")
		(at 1.3462 -146.685 90)
		(property "Reference" "C9L13"
			(at 0 0 90)
			(layer "B.SilkS")
			(hide yes)
			(effects
				(font
					(size 1.27 1.27)
				)
				(justify mirror)
			)
		)
		(property "Value" ""
			(at 0 0 90)
			(layer "B.Fab")
			(effects
				(font
					(size 1.27 1.27)
				)
				(justify mirror)
			)
		)
		(duplicate_pad_numbers_are_jumpers no)
		(fp_rect
			(start -0.7239 -0.2159)
			(end 0.7239 1.9939)
			(stroke
				(width 0)
				(type default)
			)
			(fill no)
			(layer "B.CrtYd")
		)
		(fp_line
			(start 0.7239 -0.2159)
			(end 0.7239 1.9939)
			(stroke
				(width 0.1)
				(type default)
			)
			(layer "B.Fab")
		)
		(fp_line
			(start -0.7239 -0.2159)
			(end 0.7239 -0.2159)
			(stroke
				(width 0.1)
				(type default)
			)
			(layer "B.Fab")
		)
		(fp_line
			(start 0.7239 1.9939)
			(end -0.7239 1.9939)
			(stroke
				(width 0.1)
				(type default)
			)
			(layer "B.Fab")
		)
		(fp_line
			(start -0.7239 1.9939)
			(end -0.7239 -0.2159)
			(stroke
				(width 0.1)
				(type default)
			)
			(layer "B.Fab")
		)
		(pad "1" smd rect
			(at 0 0 270)
			(size 1.27 1.016)
			(layers "B.Cu" "B.Mask" "B.Paste")
			(net "VR_FET_SW_P12V_STBY_PVDDQ_KLM")
		)
		(pad "2" smd rect
			(at 0 1.778 270)
			(size 1.27 1.016)
			(layers "B.Cu" "B.Mask" "B.Paste")
			(net "GND")
		)
		(zone
			(layer "B.Cu")
			(hatch none 0.5)
			(connect_pads
				(clearance 0)
			)
			(min_thickness 0.25)
			(keepout
				(tracks not_allowed)
				(vias allowed)
				(pads allowed)
				(copperpour not_allowed)
				(footprints allowed)
			)
			(placement
				(enabled no)
				(sheetname "")
			)
			(fill
				(thermal_gap 0.5)
				(thermal_bridge_width 0.5)
				(island_removal_mode 0)
			)
			(polygon
				(pts
					(xy 1.8542 -146.05) (xy 2.6162 -146.05) (xy 2.6162 -147.32) (xy 1.8542 -147.32)
				)
			)
		)
	)
)
